FILE_TYPE = MULTI_PHYS_TABLE;
PART 'CONN12_C73564003'
{========================================================================================}
:PACK_TYPE | MATERIAL | PART_NUMBER     = ENVCOMP                  | PART_NUMBER  | JEDEC_TYPE             | DESCRIPTION                          | CLASS | COMPONENT_TYPE | HEIGHT     | LEAD_LENGTH | SPEED_URL                                                                                                                       | STATUS   | RPL  | AML | BUS_UNIT     | DAYS ;
{========================================================================================}
'THMT'    | 'CONN'   | 'C73564-003'(!) = 'YES;YES;CNC;CNC;ok;VLD' | 'C73564-003' | 'CONN12_C73564003'     | 'CONN,HDR,2 X 6,PLG,VT,0.1,062ST,KP' | 'IO'  | 'THMT'         | '0.330 IN' | '0.085'     | 'http://speed.intel.com:8081/speed/module/pdm/item/pdm_item_detail_direct.asp?item_cde=C73564-003&item_rev=01&url_param=unused' | 'Design' | 'NO' | '1' | 'SMO_BOARDS' | '28'
'THMT'    | 'EMPTY'  | 'C73564-003'(!) = 'YES;YES;CNC;CNC;ok;VLD' | 'C73564-003' | 'CONN12_C73564003'     | 'CONN,HDR,2 X 6,PLG,VT,0.1,062ST,KP' | 'IO'  | 'THMT'         | '0.330 IN' | '0.085'     | 'http://speed.intel.com:8081/speed/module/pdm/item/pdm_item_detail_direct.asp?item_cde=C73564-003&item_rev=01&url_param=unused' | 'Design' | 'NO' | '1' | 'SMO_BOARDS' | '28'
'PIP'     | 'CONN'   | 'C73564-003'(!) = ''                       | 'C73564-003' | 'CONN12_C73564003_PIP' | 'CONN,HDR,2 X 6,PLG,VT,0.1,062ST,KP' | 'IO'  | 'THMT'         | '0.343 IN' | '0.085'     | 'http://speed.intel.com:8081/speed/module/pdm/item/pdm_item_detail_direct.asp?item_cde=C73564-003&item_rev=01&url_param=unused' | ''       | ''   | ''  | ''           | ''  
'PIP'     | 'EMPTY'  | 'C73564-003'(!) = ''                       | 'C73564-003' | 'CONN12_C73564003_PIP' | 'CONN,HDR,2 X 6,PLG,VT,0.1,062ST,KP' | 'IO'  | 'THMT'         | '0.343 IN' | '0.085'     | 'http://speed.intel.com:8081/speed/module/pdm/item/pdm_item_detail_direct.asp?item_cde=C73564-003&item_rev=01&url_param=unused' | ''       | ''   | ''  | ''           | ''  
END_PART
END.
